(kicad_pcb
	(version 20260206)
	(generator "pcbnew")
	(generator_version "10.0")
	(general
		(thickness 1.6)
		(legacy_teardrops no)
	)
	(paper "A4")
	(title_block
		(title "01162023_DA0F0TEBIF0_F0T_Expander_BD_F_brd_V02_OCP.brd")
		(comment 1 "Grand Teton / footprint 2022 of 9728 (J21), pads 110-179 of 179")
	)
	(layers
		(0 "F.Cu" signal "TOP")
		(4 "In1.Cu" signal "GND")
		(6 "In2.Cu" signal "VCC")
		(8 "In3.Cu" signal "VCC1")
		(10 "In4.Cu" signal "GND1")
		(12 "In5.Cu" signal "IN1")
		(14 "In6.Cu" signal "GND2")
		(16 "In7.Cu" signal "IN2")
		(18 "In8.Cu" signal "GND3")
		(20 "In9.Cu" signal "IN3")
		(22 "In10.Cu" signal "GND4")
		(24 "In11.Cu" signal "IN4")
		(26 "In12.Cu" signal "GND5")
		(28 "In13.Cu" signal "IN5")
		(30 "In14.Cu" signal "GND6")
		(32 "In15.Cu" signal "IN6")
		(34 "In16.Cu" signal "GND7")
		(2 "B.Cu" signal "BOTTOM")
		(9 "F.Adhes" user "F.Adhesive")
		(11 "B.Adhes" user "B.Adhesive")
		(13 "F.Paste" user "Package Geometry/Pastemask Top")
		(15 "B.Paste" user "Package Geometry/Pastemask Bottom")
		(5 "F.SilkS" user "Ref Des/Silkscreen Top")
		(7 "B.SilkS" user "Ref Des/Silkscreen Bottom")
		(1 "F.Mask" user "Board Geometry/Soldermask Top")
		(3 "B.Mask" user "Board Geometry/Soldermask Bottom")
		(17 "Dwgs.User" user "User.Drawings")
		(19 "Cmts.User" user "User.Comments")
		(21 "Eco1.User" user "User.Eco1")
		(23 "Eco2.User" user "User.Eco2")
		(25 "Edge.Cuts" user "Board Geometry/Outline")
		(27 "Margin" user)
		(31 "F.CrtYd" user "Package Geometry/Place Bound Top")
		(29 "B.CrtYd" user "Package Geometry/Place Bound Bottom")
		(35 "F.Fab" user "Ref Des/Assembly Top")
		(33 "B.Fab" user "Ref Des/Assembly Bottom")
	)
	(footprint ""
		(layer "F.Cu")
		(at 71.980044 -127.700024 180)
		(property "Reference" "J21"
			(at 5.278374 -34.786824 90)
			(unlocked yes)
			(layer "F.SilkS")
			(effects
				(font
					(size 0.7874 0.5842)
					(thickness 0.1524)
				)
				(justify left)
			)
		)
		(property "Value" ""
			(at 0 0 180)
			(layer "F.Fab")
			(effects
				(font
					(size 1.27 1.27)
				)
			)
		)
		(duplicate_pad_numbers_are_jumpers no)
		(pad "B38" smd rect
			(at -1.27762 7.14502 90)
			(size 0.3556 1.2192)
			(layers "F.Cu" "F.Mask" "F.Paste")
			(net "GND")
		)
		(pad "B39" smd rect
			(at -1.27762 7.744968 90)
			(size 0.3556 1.2192)
			(layers "F.Cu" "F.Mask" "F.Paste")
			(net "P5E_PEX0_STN0_TX_C_DN<7>")
		)
		(pad "B40" smd rect
			(at -1.27762 8.344916 90)
			(size 0.3556 1.2192)
			(layers "F.Cu" "F.Mask" "F.Paste")
			(net "P5E_PEX0_STN0_TX_C_DP<7>")
		)
		(pad "B41" smd rect
			(at -1.27762 8.945118 90)
			(size 0.3556 1.2192)
			(layers "F.Cu" "F.Mask" "F.Paste")
			(net "GND")
		)
		(pad "B42" smd rect
			(at -1.27762 9.545066 90)
			(size 0.3556 1.2192)
			(layers "F.Cu" "F.Mask" "F.Paste")
			(net "PRSNTB0_NIC1_N")
		)
		(pad "B43" smd rect
			(at -1.27762 14.454886 90)
			(size 0.3556 1.2192)
			(layers "F.Cu" "F.Mask" "F.Paste")
			(net "GND")
		)
		(pad "B44" smd rect
			(at -1.27762 15.055088 90)
			(size 0.3556 1.2192)
			(layers "F.Cu" "F.Mask" "F.Paste")
			(net "P5E_PEX0_STN0_TX_C_DN<8>")
		)
		(pad "B45" smd rect
			(at -1.27762 15.655036 90)
			(size 0.3556 1.2192)
			(layers "F.Cu" "F.Mask" "F.Paste")
			(net "P5E_PEX0_STN0_TX_C_DP<8>")
		)
		(pad "B46" smd rect
			(at -1.27762 16.254984 90)
			(size 0.3556 1.2192)
			(layers "F.Cu" "F.Mask" "F.Paste")
			(net "GND")
		)
		(pad "B47" smd rect
			(at -1.27762 16.854932 90)
			(size 0.3556 1.2192)
			(layers "F.Cu" "F.Mask" "F.Paste")
			(net "P5E_PEX0_STN0_TX_C_DN<9>")
		)
		(pad "B48" smd rect
			(at -1.27762 17.45488 90)
			(size 0.3556 1.2192)
			(layers "F.Cu" "F.Mask" "F.Paste")
			(net "P5E_PEX0_STN0_TX_C_DP<9>")
		)
		(pad "B49" smd rect
			(at -1.27762 18.055082 90)
			(size 0.3556 1.2192)
			(layers "F.Cu" "F.Mask" "F.Paste")
			(net "GND")
		)
		(pad "B50" smd rect
			(at -1.27762 18.65503 90)
			(size 0.3556 1.2192)
			(layers "F.Cu" "F.Mask" "F.Paste")
			(net "P5E_PEX0_STN0_TX_C_DN<10>")
		)
		(pad "B51" smd rect
			(at -1.27762 19.254978 90)
			(size 0.3556 1.2192)
			(layers "F.Cu" "F.Mask" "F.Paste")
			(net "P5E_PEX0_STN0_TX_C_DP<10>")
		)
		(pad "B52" smd rect
			(at -1.27762 19.854926 90)
			(size 0.3556 1.2192)
			(layers "F.Cu" "F.Mask" "F.Paste")
			(net "GND")
		)
		(pad "B53" smd rect
			(at -1.27762 20.455128 90)
			(size 0.3556 1.2192)
			(layers "F.Cu" "F.Mask" "F.Paste")
			(net "P5E_PEX0_STN0_TX_C_DN<11>")
		)
		(pad "B54" smd rect
			(at -1.27762 21.055076 90)
			(size 0.3556 1.2192)
			(layers "F.Cu" "F.Mask" "F.Paste")
			(net "P5E_PEX0_STN0_TX_C_DP<11>")
		)
		(pad "B55" smd rect
			(at -1.27762 21.655024 90)
			(size 0.3556 1.2192)
			(layers "F.Cu" "F.Mask" "F.Paste")
			(net "GND")
		)
		(pad "B56" smd rect
			(at -1.27762 22.254972 90)
			(size 0.3556 1.2192)
			(layers "F.Cu" "F.Mask" "F.Paste")
			(net "P5E_PEX0_STN0_TX_C_DP<12>")
		)
		(pad "B57" smd rect
			(at -1.27762 22.85492 90)
			(size 0.3556 1.2192)
			(layers "F.Cu" "F.Mask" "F.Paste")
			(net "P5E_PEX0_STN0_TX_C_DN<12>")
		)
		(pad "B58" smd rect
			(at -1.27762 23.455122 90)
			(size 0.3556 1.2192)
			(layers "F.Cu" "F.Mask" "F.Paste")
			(net "GND")
		)
		(pad "B59" smd rect
			(at -1.27762 24.05507 90)
			(size 0.3556 1.2192)
			(layers "F.Cu" "F.Mask" "F.Paste")
			(net "P5E_PEX0_STN0_TX_C_DN<13>")
		)
		(pad "B60" smd rect
			(at -1.27762 24.655018 90)
			(size 0.3556 1.2192)
			(layers "F.Cu" "F.Mask" "F.Paste")
			(net "P5E_PEX0_STN0_TX_C_DP<13>")
		)
		(pad "B61" smd rect
			(at -1.27762 25.254966 90)
			(size 0.3556 1.2192)
			(layers "F.Cu" "F.Mask" "F.Paste")
			(net "GND")
		)
		(pad "B62" smd rect
			(at -1.27762 25.854914 90)
			(size 0.3556 1.2192)
			(layers "F.Cu" "F.Mask" "F.Paste")
			(net "P5E_PEX0_STN0_TX_C_DP<14>")
		)
		(pad "B63" smd rect
			(at -1.27762 26.455116 90)
			(size 0.3556 1.2192)
			(layers "F.Cu" "F.Mask" "F.Paste")
			(net "P5E_PEX0_STN0_TX_C_DN<14>")
		)
		(pad "B64" smd rect
			(at -1.27762 27.055064 90)
			(size 0.3556 1.2192)
			(layers "F.Cu" "F.Mask" "F.Paste")
			(net "GND")
		)
		(pad "B65" smd rect
			(at -1.27762 27.655012 90)
			(size 0.3556 1.2192)
			(layers "F.Cu" "F.Mask" "F.Paste")
			(net "P5E_PEX0_STN0_TX_C_DN<15>")
		)
		(pad "B66" smd rect
			(at -1.27762 28.25496 90)
			(size 0.3556 1.2192)
			(layers "F.Cu" "F.Mask" "F.Paste")
			(net "P5E_PEX0_STN0_TX_C_DP<15>")
		)
		(pad "B67" smd rect
			(at -1.27762 28.854908 90)
			(size 0.3556 1.2192)
			(layers "F.Cu" "F.Mask" "F.Paste")
			(net "GND")
		)
		(pad "B68" smd rect
			(at -1.27762 29.45511 90)
			(size 0.3556 1.2192)
			(layers "F.Cu" "F.Mask" "F.Paste")
			(net "Net_2594")
		)
		(pad "B69" smd rect
			(at -1.27762 30.055058 90)
			(size 0.3556 1.2192)
			(layers "F.Cu" "F.Mask" "F.Paste")
			(net "Net_2595")
		)
		(pad "B70" smd rect
			(at -1.27762 30.655006 90)
			(size 0.3556 1.2192)
			(layers "F.Cu" "F.Mask" "F.Paste")
			(net "PRSNTB3_NIC1_N")
		)
		(pad "G1" thru_hole oval
			(at 1.022604 -34.034984 90)
			(size 1.6256 3.4798)
			(drill oval 1.1176 2.4638)
			(layers "*.Cu" "*.Mask")
			(remove_unused_layers no)
			(net "GND")
			(clearance 0.127)
			(thermal_gap 0.127)
		)
		(pad "G2" thru_hole oval
			(at 1.022604 -20.625054 90)
			(size 1.6256 3.4798)
			(drill oval 1.1176 2.4638)
			(layers "*.Cu" "*.Mask")
			(remove_unused_layers no)
			(net "GND")
			(clearance 0.127)
			(thermal_gap 0.127)
		)
		(pad "G3" thru_hole oval
			(at 1.022604 -0.255016 90)
			(size 1.6256 3.4798)
			(drill oval 1.1176 2.4638)
			(layers "*.Cu" "*.Mask")
			(remove_unused_layers no)
			(net "GND")
			(clearance 0.127)
			(thermal_gap 0.127)
		)
		(pad "G4" thru_hole oval
			(at 1.022604 12.005056 90)
			(size 1.6256 3.4798)
			(drill oval 1.1176 2.4638)
			(layers "*.Cu" "*.Mask")
			(remove_unused_layers no)
			(net "GND")
			(clearance 0.127)
			(thermal_gap 0.127)
		)
		(pad "G5" thru_hole oval
			(at 1.022604 34.034984 90)
			(size 1.5748 3.4798)
			(drill oval 1.1176 2.4638)
			(layers "*.Cu" "*.Mask")
			(remove_unused_layers no)
			(net "GND")
			(clearance 0.1524)
			(thermal_gap 0.1524)
		)
		(pad "G6" thru_hole circle
			(at -3.16738 -20.625054 180)
			(size 1.6256 1.6256)
			(drill 1.1176)
			(layers "*.Cu" "*.Mask")
			(remove_unused_layers no)
			(net "GND")
			(clearance 0)
		)
		(pad "G7" thru_hole circle
			(at -3.16738 12.005056 180)
			(size 1.6256 1.6256)
			(drill 1.1176)
			(layers "*.Cu" "*.Mask")
			(remove_unused_layers no)
			(net "GND")
			(clearance 0)
		)
		(pad "G8" thru_hole circle
			(at 4.20243 -20.625054 180)
			(size 1.6256 1.6256)
			(drill 1.1176)
			(layers "*.Cu" "*.Mask")
			(remove_unused_layers no)
			(net "GND")
			(clearance 0)
		)
		(pad "G9" thru_hole circle
			(at 4.20243 12.005056 180)
			(size 1.6256 1.6256)
			(drill 1.1176)
			(layers "*.Cu" "*.Mask")
			(remove_unused_layers no)
			(net "GND")
			(clearance 0)
		)
		(pad "OA1" smd rect
			(at 3.322574 -30.660086 90)
			(size 0.3556 1.2192)
			(layers "F.Cu" "F.Mask" "F.Paste")
			(net "RST_NIC1_PERST2_R_N")
		)
		(pad "OA2" smd rect
			(at 3.322574 -30.059884 90)
			(size 0.3556 1.2192)
			(layers "F.Cu" "F.Mask" "F.Paste")
			(net "RST_NIC1_PERST3_R_N")
		)
		(pad "OA3" smd rect
			(at 3.322574 -29.459936 90)
			(size 0.3556 1.2192)
			(layers "F.Cu" "F.Mask" "F.Paste")
			(net "Net_2598")
		)
		(pad "OA4" smd rect
			(at 3.322574 -28.859988 90)
			(size 0.3556 1.2192)
			(layers "F.Cu" "F.Mask" "F.Paste")
			(net "NIC1_RBT_ARB_IN")
		)
		(pad "OA5" smd rect
			(at 3.322574 -28.26004 90)
			(size 0.3556 1.2192)
			(layers "F.Cu" "F.Mask" "F.Paste")
			(net "NIC1_RBT_ARB_OUT")
		)
		(pad "OA6" smd rect
			(at 3.322574 -27.660092 90)
			(size 0.3556 1.2192)
			(layers "F.Cu" "F.Mask" "F.Paste")
			(net "NIC1_SLOT_ID1")
		)
		(pad "OA7" smd rect
			(at 3.322574 -27.05989 90)
			(size 0.3556 1.2192)
			(layers "F.Cu" "F.Mask" "F.Paste")
			(net "NCSI_NIC1_TX_EN")
		)
		(pad "OA8" smd rect
			(at 3.322574 -26.459942 90)
			(size 0.3556 1.2192)
			(layers "F.Cu" "F.Mask" "F.Paste")
			(net "NCSI_NIC1_TXD1")
		)
		(pad "OA9" smd rect
			(at 3.322574 -25.859994 90)
			(size 0.3556 1.2192)
			(layers "F.Cu" "F.Mask" "F.Paste")
			(net "NCSI_NIC1_TXD0")
		)
		(pad "OA10" smd rect
			(at 3.322574 -25.260046 90)
			(size 0.3556 1.2192)
			(layers "F.Cu" "F.Mask" "F.Paste")
			(net "GND")
		)
		(pad "OA11" smd rect
			(at 3.322574 -24.660098 90)
			(size 0.3556 1.2192)
			(layers "F.Cu" "F.Mask" "F.Paste")
			(net "Net_2590")
		)
		(pad "OA12" smd rect
			(at 3.322574 -24.059896 90)
			(size 0.3556 1.2192)
			(layers "F.Cu" "F.Mask" "F.Paste")
			(net "Net_2593")
		)
		(pad "OA13" smd rect
			(at 3.322574 -23.459948 90)
			(size 0.3556 1.2192)
			(layers "F.Cu" "F.Mask" "F.Paste")
			(net "GND")
		)
		(pad "OA14" smd rect
			(at 3.322574 -22.86 90)
			(size 0.3556 1.2192)
			(layers "F.Cu" "F.Mask" "F.Paste")
			(net "CLK_50M_NIC1_RBT_REF")
		)
		(pad "OB1" smd rect
			(at -1.27762 -30.660086 90)
			(size 0.3556 1.2192)
			(layers "F.Cu" "F.Mask" "F.Paste")
			(net "PWRGD_NIC1_PWR_GOOD")
		)
		(pad "OB2" smd rect
			(at -1.27762 -30.059884 90)
			(size 0.3556 1.2192)
			(layers "F.Cu" "F.Mask" "F.Paste")
			(net "NIC1_MAIN_PWR_EN_R")
		)
		(pad "OB3" smd rect
			(at -1.27762 -29.459936 90)
			(size 0.3556 1.2192)
			(layers "F.Cu" "F.Mask" "F.Paste")
			(net "NIC1_LD_N")
		)
		(pad "OB4" smd rect
			(at -1.27762 -28.859988 90)
			(size 0.3556 1.2192)
			(layers "F.Cu" "F.Mask" "F.Paste")
			(net "NIC1_DATA_IN")
		)
		(pad "OB5" smd rect
			(at -1.27762 -28.26004 90)
			(size 0.3556 1.2192)
			(layers "F.Cu" "F.Mask" "F.Paste")
			(net "NIC1_DATA_OUT")
		)
		(pad "OB6" smd rect
			(at -1.27762 -27.660092 90)
			(size 0.3556 1.2192)
			(layers "F.Cu" "F.Mask" "F.Paste")
			(net "NIC1_CLK")
		)
		(pad "OB7" smd rect
			(at -1.27762 -27.05989 90)
			(size 0.3556 1.2192)
			(layers "F.Cu" "F.Mask" "F.Paste")
			(net "NIC1_SLOT_ID0")
		)
		(pad "OB8" smd rect
			(at -1.27762 -26.459942 90)
			(size 0.3556 1.2192)
			(layers "F.Cu" "F.Mask" "F.Paste")
			(net "NCSI_NIC1_RXD1")
		)
		(pad "OB9" smd rect
			(at -1.27762 -25.859994 90)
			(size 0.3556 1.2192)
			(layers "F.Cu" "F.Mask" "F.Paste")
			(net "NCSI_NIC1_RXD0")
		)
		(pad "OB10" smd rect
			(at -1.27762 -25.260046 90)
			(size 0.3556 1.2192)
			(layers "F.Cu" "F.Mask" "F.Paste")
			(net "GND")
		)
		(pad "OB11" smd rect
			(at -1.27762 -24.660098 90)
			(size 0.3556 1.2192)
			(layers "F.Cu" "F.Mask" "F.Paste")
			(net "Net_2589")
		)
		(pad "OB12" smd rect
			(at -1.27762 -24.059896 90)
			(size 0.3556 1.2192)
			(layers "F.Cu" "F.Mask" "F.Paste")
			(net "Net_2592")
		)
		(pad "OB13" smd rect
			(at -1.27762 -23.459948 90)
			(size 0.3556 1.2192)
			(layers "F.Cu" "F.Mask" "F.Paste")
			(net "GND")
		)
		(pad "OB14" smd rect
			(at -1.27762 -22.86 90)
			(size 0.3556 1.2192)
			(layers "F.Cu" "F.Mask" "F.Paste")
			(net "NCSI_NIC1_CRS_DV")
		)
	)
)
